# T6G (Grand Teton) — schematic netlist excerpt (pin names and nets, part order shuffled) for the footprints in the layout excerpt that follows; sources: Cadence DE-HDL packaged netlist, KiCad conversion of 04192023_DAF0TMB3IC0_F0TG_MB_C_brd_V02_OCP.brd

R168  Q_RES  0 5% CHIP  pkg 0402LF  page 80 : A = SGPIO_SCM_DI_R<1> ; B = SGPIO_SCM_DI_<1>
R2924  Q_RES  49.9 1% CHIP  pkg 0402LF  page 130 : A = RST_SWB_BIC_BUF_R_N ; B = RST_SWB_BIC_BUF_N

(kicad_pcb
	(version 20260206)
	(generator "pcbnew")
	(generator_version "10.0")
	(general
		(thickness 1.6)
		(legacy_teardrops no)
	)
	(paper "A4")
	(title_block
		(title "04192023_DAF0TMB3IC0_F0TG_MB_C_brd_V02_OCP.brd")
		(comment 1 "Grand Teton / footprints 7498-7499 of 8354")
	)
	(layers
		(0 "F.Cu" signal "TOP")
		(4 "In1.Cu" signal "GND")
		(6 "In2.Cu" signal "IN1")
		(8 "In3.Cu" signal "GND1")
		(10 "In4.Cu" signal "IN2")
		(12 "In5.Cu" signal "GND2")
		(14 "In6.Cu" signal "IN3")
		(16 "In7.Cu" signal "GND3")
		(18 "In8.Cu" signal "VCC")
		(20 "In9.Cu" signal "VCC1")
		(22 "In10.Cu" signal "GND4")
		(24 "In11.Cu" signal "IN4")
		(26 "In12.Cu" signal "GND5")
		(28 "In13.Cu" signal "IN5")
		(30 "In14.Cu" signal "GND6")
		(32 "In15.Cu" signal "IN6")
		(34 "In16.Cu" signal "GND7")
		(2 "B.Cu" signal "BOTTOM")
		(9 "F.Adhes" user "F.Adhesive")
		(11 "B.Adhes" user "B.Adhesive")
		(13 "F.Paste" user "Package Geometry/Pastemask Top")
		(15 "B.Paste" user "Package Geometry/Pastemask Bottom")
		(5 "F.SilkS" user "Ref Des/Silkscreen Top")
		(7 "B.SilkS" user "Ref Des/Silkscreen Bottom")
		(1 "F.Mask" user "Board Geometry/Soldermask Top")
		(3 "B.Mask" user "Board Geometry/Soldermask Bottom")
		(17 "Dwgs.User" user "User.Drawings")
		(19 "Cmts.User" user "User.Comments")
		(21 "Eco1.User" user "User.Eco1")
		(23 "Eco2.User" user "User.Eco2")
		(25 "Edge.Cuts" user "Board Geometry/Outline")
		(27 "Margin" user)
		(31 "F.CrtYd" user "Package Geometry/Place Bound Top")
		(29 "B.CrtYd" user "Package Geometry/Place Bound Bottom")
		(35 "F.Fab" user "Ref Des/Assembly Top")
		(33 "B.Fab" user "Ref Des/Assembly Bottom")
	)
	(footprint ""
		(layer "B.Cu")
		(at 171.196 -110.200948)
		(property "Reference" "R168"
			(at 0 0 0)
			(layer "B.SilkS")
			(hide yes)
			(effects
				(font
					(size 1.27 1.27)
				)
				(justify mirror)
			)
		)
		(property "Value" ""
			(at 0 0 0)
			(layer "B.Fab")
			(effects
				(font
					(size 1.27 1.27)
				)
				(justify mirror)
			)
		)
		(duplicate_pad_numbers_are_jumpers no)
		(fp_line
			(start -0.7874 -0.4064)
			(end -0.7874 0.4064)
			(stroke
				(width 0.1524)
				(type default)
			)
			(layer "B.SilkS")
		)
		(fp_line
			(start -0.7874 0.4064)
			(end 0.7874 0.4064)
			(stroke
				(width 0.1524)
				(type default)
			)
			(layer "B.SilkS")
		)
		(fp_line
			(start 0.7874 -0.4064)
			(end -0.7874 -0.4064)
			(stroke
				(width 0.1524)
				(type default)
			)
			(layer "B.SilkS")
		)
		(fp_line
			(start 0.7874 0.4064)
			(end 0.7874 -0.4064)
			(stroke
				(width 0.1524)
				(type default)
			)
			(layer "B.SilkS")
		)
		(fp_line
			(start -0.67945 -0.3048)
			(end -0.67945 0.3048)
			(stroke
				(width 0.1)
				(type default)
			)
			(layer "B.Fab")
		)
		(fp_line
			(start -0.67945 0.3048)
			(end -0.120396 0.3048)
			(stroke
				(width 0.1)
				(type default)
			)
			(layer "B.Fab")
		)
		(fp_line
			(start -0.12065 -0.3048)
			(end -0.67945 -0.3048)
			(stroke
				(width 0.1)
				(type default)
			)
			(layer "B.Fab")
		)
		(fp_line
			(start -0.12065 -0.2794)
			(end -0.12065 -0.3048)
			(stroke
				(width 0.1)
				(type default)
			)
			(layer "B.Fab")
		)
		(fp_line
			(start -0.120396 0.2794)
			(end 0.12065 0.2794)
			(stroke
				(width 0.1)
				(type default)
			)
			(layer "B.Fab")
		)
		(fp_line
			(start -0.120396 0.3048)
			(end -0.120396 0.2794)
			(stroke
				(width 0.1)
				(type default)
			)
			(layer "B.Fab")
		)
		(fp_line
			(start 0.12065 -0.305054)
			(end 0.12065 -0.2794)
			(stroke
				(width 0.1)
				(type default)
			)
			(layer "B.Fab")
		)
		(fp_line
			(start 0.12065 -0.2794)
			(end -0.12065 -0.2794)
			(stroke
				(width 0.1)
				(type default)
			)
			(layer "B.Fab")
		)
		(fp_line
			(start 0.12065 0.2794)
			(end 0.12065 0.3048)
			(stroke
				(width 0.1)
				(type default)
			)
			(layer "B.Fab")
		)
		(fp_line
			(start 0.12065 0.3048)
			(end 0.67945 0.3048)
			(stroke
				(width 0.1)
				(type default)
			)
			(layer "B.Fab")
		)
		(fp_line
			(start 0.67945 -0.305054)
			(end 0.12065 -0.305054)
			(stroke
				(width 0.1)
				(type default)
			)
			(layer "B.Fab")
		)
		(fp_line
			(start 0.67945 0.3048)
			(end 0.67945 -0.305054)
			(stroke
				(width 0.1)
				(type default)
			)
			(layer "B.Fab")
		)
		(pad "1" smd circle
			(at 0.40005 0 180)
			(size 0 0)
			(layers "B.Cu" "B.Mask" "B.Paste")
			(net "SGPIO_SCM_DI_R<1>")
		)
		(pad "2" smd circle
			(at -0.40005 0 180)
			(size 0 0)
			(layers "B.Cu" "B.Mask" "B.Paste")
			(net "SGPIO_SCM_DI_<1>")
		)
	)
	(footprint ""
		(layer "B.Cu")
		(at 182.801768 -414.772094 180)
		(property "Reference" "R2924"
			(at 0 0 0)
			(layer "B.SilkS")
			(hide yes)
			(effects
				(font
					(size 1.27 1.27)
				)
				(justify mirror)
			)
		)
		(property "Value" ""
			(at 0 0 0)
			(layer "B.Fab")
			(effects
				(font
					(size 1.27 1.27)
				)
				(justify mirror)
			)
		)
		(duplicate_pad_numbers_are_jumpers no)
		(fp_line
			(start 0.7874 0.4064)
			(end 0.7874 -0.4064)
			(stroke
				(width 0.1524)
				(type default)
			)
			(layer "B.SilkS")
		)
		(fp_line
			(start 0.7874 -0.4064)
			(end -0.7874 -0.4064)
			(stroke
				(width 0.1524)
				(type default)
			)
			(layer "B.SilkS")
		)
		(fp_line
			(start -0.7874 0.4064)
			(end 0.7874 0.4064)
			(stroke
				(width 0.1524)
				(type default)
			)
			(layer "B.SilkS")
		)
		(fp_line
			(start -0.7874 -0.4064)
			(end -0.7874 0.4064)
			(stroke
				(width 0.1524)
				(type default)
			)
			(layer "B.SilkS")
		)
		(fp_line
			(start 0.67945 0.3048)
			(end 0.67945 -0.305054)
			(stroke
				(width 0.1)
				(type default)
			)
			(layer "B.Fab")
		)
		(fp_line
			(start 0.67945 -0.305054)
			(end 0.12065 -0.305054)
			(stroke
				(width 0.1)
				(type default)
			)
			(layer "B.Fab")
		)
		(fp_line
			(start 0.12065 0.3048)
			(end 0.67945 0.3048)
			(stroke
				(width 0.1)
				(type default)
			)
			(layer "B.Fab")
		)
		(fp_line
			(start 0.12065 0.2794)
			(end 0.12065 0.3048)
			(stroke
				(width 0.1)
				(type default)
			)
			(layer "B.Fab")
		)
		(fp_line
			(start 0.12065 -0.2794)
			(end -0.12065 -0.2794)
			(stroke
				(width 0.1)
				(type default)
			)
			(layer "B.Fab")
		)
		(fp_line
			(start 0.12065 -0.305054)
			(end 0.12065 -0.2794)
			(stroke
				(width 0.1)
				(type default)
			)
			(layer "B.Fab")
		)
		(fp_line
			(start -0.120396 0.3048)
			(end -0.120396 0.2794)
			(stroke
				(width 0.1)
				(type default)
			)
			(layer "B.Fab")
		)
		(fp_line
			(start -0.120396 0.2794)
			(end 0.12065 0.2794)
			(stroke
				(width 0.1)
				(type default)
			)
			(layer "B.Fab")
		)
		(fp_line
			(start -0.12065 -0.2794)
			(end -0.12065 -0.3048)
			(stroke
				(width 0.1)
				(type default)
			)
			(layer "B.Fab")
		)
		(fp_line
			(start -0.12065 -0.3048)
			(end -0.67945 -0.3048)
			(stroke
				(width 0.1)
				(type default)
			)
			(layer "B.Fab")
		)
		(fp_line
			(start -0.67945 0.3048)
			(end -0.120396 0.3048)
			(stroke
				(width 0.1)
				(type default)
			)
			(layer "B.Fab")
		)
		(fp_line
			(start -0.67945 -0.3048)
			(end -0.67945 0.3048)
			(stroke
				(width 0.1)
				(type default)
			)
			(layer "B.Fab")
		)
		(pad "1" smd circle
			(at 0.40005 0)
			(size 0 0)
			(layers "B.Cu" "B.Mask" "B.Paste")
			(net "RST_SWB_BIC_BUF_R_N")
		)
		(pad "2" smd circle
			(at -0.40005 0)
			(size 0 0)
			(layers "B.Cu" "B.Mask" "B.Paste")
			(net "RST_SWB_BIC_BUF_N")
		)
	)
)
